(kicad_pcb
	(version 20260206)
	(generator "pcbnew")
	(generator_version "10.0")
	(general
		(thickness 1.6)
		(legacy_teardrops no)
	)
	(paper "A4")
	(title_block
		(title "Bryce Canyon_R.DPB_16317-1_OCP.brd")
		(comment 1 "Bryce Canyon / footprint 1305 of 2099 (PCIE1), pads 1-73 of 76")
	)
	(layers
		(0 "F.Cu" signal "TOP")
		(4 "In1.Cu" signal "L2GND")
		(6 "In2.Cu" signal "L3")
		(8 "In3.Cu" signal "L4VCC")
		(10 "In4.Cu" signal "L5VCC")
		(12 "In5.Cu" signal "L6")
		(14 "In6.Cu" signal "L7GND")
		(2 "B.Cu" signal "BOTTOM")
		(9 "F.Adhes" user "F.Adhesive")
		(11 "B.Adhes" user "B.Adhesive")
		(13 "F.Paste" user "Package Geometry/Pastemask Top")
		(15 "B.Paste" user "Package Geometry/Pastemask Bottom")
		(5 "F.SilkS" user "Ref Des/Silkscreen Top")
		(7 "B.SilkS" user "Ref Des/Silkscreen Bottom")
		(1 "F.Mask" user "Board Geometry/Soldermask Top")
		(3 "B.Mask" user "Board Geometry/Soldermask Bottom")
		(17 "Dwgs.User" user "User.Drawings")
		(19 "Cmts.User" user "User.Comments")
		(21 "Eco1.User" user "User.Eco1")
		(23 "Eco2.User" user "User.Eco2")
		(25 "Edge.Cuts" user "Board Geometry/Outline")
		(27 "Margin" user)
		(31 "F.CrtYd" user "Package Geometry/Place Bound Top")
		(29 "B.CrtYd" user "Package Geometry/Place Bound Bottom")
		(35 "F.Fab" user "Ref Des/Assembly Top")
		(33 "B.Fab" user "Ref Des/Assembly Bottom")
	)
	(footprint ""
		(layer "F.Cu")
		(at 287.83661 -144.694402 -90)
		(property "Reference" "PCIE1"
			(at 0 0 270)
			(layer "F.SilkS")
			(hide yes)
			(effects
				(font
					(size 1.27 1.27)
				)
			)
		)
		(property "Value" "AMP-CONN76-8R-5-GP"
			(at -8.9408 -15.1892 270)
			(unlocked yes)
			(layer "F.Fab")
			(hide yes)
			(effects
				(font
					(size 1.016 1.016)
					(thickness 0.1524)
				)
			)
		)
		(property "Device Type" "PREFIT-76P-165151H483"
			(at -8.9408 -16.7132 270)
			(unlocked yes)
			(layer "F.Fab")
			(hide yes)
			(effects
				(font
					(size 1.016 1.016)
					(thickness 0.1524)
				)
			)
		)
		(duplicate_pad_numbers_are_jumpers no)
		(pad "A1" thru_hole circle
			(at 0 0 270)
			(size 0.762 0.762)
			(drill 0.359918)
			(layers "*.Cu" "*.Mask")
			(remove_unused_layers no)
			(net "PCIE_COMP_B_TO_SCC_B_0_DP")
			(clearance 0.1651)
			(thermal_gap 0.1651)
		)
		(pad "A2" thru_hole circle
			(at 1.800098 0.999998 270)
			(size 0.762 0.762)
			(drill 0.359918)
			(layers "*.Cu" "*.Mask")
			(remove_unused_layers no)
			(net "PCIE_COMP_B_TO_SCC_B_1_DP")
			(clearance 0.1651)
			(thermal_gap 0.1651)
		)
		(pad "A3" thru_hole circle
			(at 3.599942 0 270)
			(size 0.762 0.762)
			(drill 0.359918)
			(layers "*.Cu" "*.Mask")
			(remove_unused_layers no)
			(net "PCIE_COMP_B_TO_SCC_B_2_DP")
			(clearance 0.1651)
			(thermal_gap 0.1651)
		)
		(pad "A4" thru_hole circle
			(at 5.40004 0.999998 270)
			(size 0.762 0.762)
			(drill 0.359918)
			(layers "*.Cu" "*.Mask")
			(remove_unused_layers no)
			(net "PCIE_COMP_B_TO_SCC_B_3_DP")
			(clearance 0.1651)
			(thermal_gap 0.1651)
		)
		(pad "A5" thru_hole circle
			(at 7.199884 0 270)
			(size 0.762 0.762)
			(drill 0.359918)
			(layers "*.Cu" "*.Mask")
			(remove_unused_layers no)
			(net "PCIE_COMP_B_TO_SCC_B_4_DP")
			(clearance 0.1651)
			(thermal_gap 0.1651)
		)
		(pad "A6" thru_hole circle
			(at 8.999982 0.999998 270)
			(size 0.762 0.762)
			(drill 0.359918)
			(layers "*.Cu" "*.Mask")
			(remove_unused_layers no)
			(net "PCIE_COMP_B_TO_SCC_B_5_DP")
			(clearance 0.1651)
			(thermal_gap 0.1651)
		)
		(pad "A7" thru_hole circle
			(at 10.80008 0 270)
			(size 0.762 0.762)
			(drill 0.359918)
			(layers "*.Cu" "*.Mask")
			(remove_unused_layers no)
			(net "PCIE_COMP_B_TO_SCC_B_6_DP")
			(clearance 0.1651)
			(thermal_gap 0.1651)
		)
		(pad "A8" thru_hole circle
			(at 12.599924 0.999998 270)
			(size 0.762 0.762)
			(drill 0.359918)
			(layers "*.Cu" "*.Mask")
			(remove_unused_layers no)
			(net "PCIE_COMP_B_TO_SCC_B_7_DP")
			(clearance 0.1651)
			(thermal_gap 0.1651)
		)
		(pad "B1" thru_hole circle
			(at 0 1.400048 270)
			(size 0.762 0.762)
			(drill 0.359918)
			(layers "*.Cu" "*.Mask")
			(remove_unused_layers no)
			(net "PCIE_COMP_B_TO_SCC_B_0_DN")
			(clearance 0.1651)
			(thermal_gap 0.1651)
		)
		(pad "B2" thru_hole circle
			(at 1.800098 2.400046 270)
			(size 0.762 0.762)
			(drill 0.359918)
			(layers "*.Cu" "*.Mask")
			(remove_unused_layers no)
			(net "PCIE_COMP_B_TO_SCC_B_1_DN")
			(clearance 0.1651)
			(thermal_gap 0.1651)
		)
		(pad "B3" thru_hole circle
			(at 3.599942 1.400048 270)
			(size 0.762 0.762)
			(drill 0.359918)
			(layers "*.Cu" "*.Mask")
			(remove_unused_layers no)
			(net "PCIE_COMP_B_TO_SCC_B_2_DN")
			(clearance 0.1651)
			(thermal_gap 0.1651)
		)
		(pad "B4" thru_hole circle
			(at 5.40004 2.400046 270)
			(size 0.762 0.762)
			(drill 0.359918)
			(layers "*.Cu" "*.Mask")
			(remove_unused_layers no)
			(net "PCIE_COMP_B_TO_SCC_B_3_DN")
			(clearance 0.1651)
			(thermal_gap 0.1651)
		)
		(pad "B5" thru_hole circle
			(at 7.199884 1.400048 270)
			(size 0.762 0.762)
			(drill 0.359918)
			(layers "*.Cu" "*.Mask")
			(remove_unused_layers no)
			(net "PCIE_COMP_B_TO_SCC_B_4_DN")
			(clearance 0.1651)
			(thermal_gap 0.1651)
		)
		(pad "B6" thru_hole circle
			(at 8.999982 2.400046 270)
			(size 0.762 0.762)
			(drill 0.359918)
			(layers "*.Cu" "*.Mask")
			(remove_unused_layers no)
			(net "PCIE_COMP_B_TO_SCC_B_5_DN")
			(clearance 0.1651)
			(thermal_gap 0.1651)
		)
		(pad "B7" thru_hole circle
			(at 10.80008 1.400048 270)
			(size 0.762 0.762)
			(drill 0.359918)
			(layers "*.Cu" "*.Mask")
			(remove_unused_layers no)
			(net "PCIE_COMP_B_TO_SCC_B_6_DN")
			(clearance 0.1651)
			(thermal_gap 0.1651)
		)
		(pad "B8" thru_hole circle
			(at 12.599924 2.400046 270)
			(size 0.762 0.762)
			(drill 0.359918)
			(layers "*.Cu" "*.Mask")
			(remove_unused_layers no)
			(net "PCIE_COMP_B_TO_SCC_B_7_DN")
			(clearance 0.1651)
			(thermal_gap 0.1651)
		)
		(pad "C1" thru_hole circle
			(at 0 3.599942 270)
			(size 0.762 0.762)
			(drill 0.359918)
			(layers "*.Cu" "*.Mask")
			(remove_unused_layers no)
			(net "PCIE_COMP_B_TO_SCC_B_CLK_0_DP")
			(clearance 0.1651)
			(thermal_gap 0.1651)
		)
		(pad "C2" thru_hole circle
			(at 1.800098 4.59994 270)
			(size 0.762 0.762)
			(drill 0.359918)
			(layers "*.Cu" "*.Mask")
			(remove_unused_layers no)
			(net "I2C_BMC_A_EXP_B_SCL")
			(clearance 0.1651)
			(thermal_gap 0.1651)
		)
		(pad "C3" thru_hole circle
			(at 3.599942 3.599942 270)
			(size 0.762 0.762)
			(drill 0.359918)
			(layers "*.Cu" "*.Mask")
			(remove_unused_layers no)
			(net "I2C_SCC_B_SCL_BUF")
			(clearance 0.1651)
			(thermal_gap 0.1651)
		)
		(pad "C4" thru_hole circle
			(at 5.40004 4.59994 270)
			(size 0.762 0.762)
			(drill 0.359918)
			(layers "*.Cu" "*.Mask")
			(remove_unused_layers no)
			(net "COMP_B_EXP_B_SPARE_0")
			(clearance 0.1651)
			(thermal_gap 0.1651)
		)
		(pad "C5" thru_hole circle
			(at 7.199884 3.599942 270)
			(size 0.762 0.762)
			(drill 0.359918)
			(layers "*.Cu" "*.Mask")
			(remove_unused_layers no)
			(net "UART_IOC_B_TX")
			(clearance 0.1651)
			(thermal_gap 0.1651)
		)
		(pad "C6" thru_hole circle
			(at 8.999982 4.59994 270)
			(size 0.762 0.762)
			(drill 0.359918)
			(layers "*.Cu" "*.Mask")
			(remove_unused_layers no)
			(net "BMC_B_EXP_B_SPARE_0")
			(clearance 0.1651)
			(thermal_gap 0.1651)
		)
		(pad "C7" thru_hole circle
			(at 10.80008 3.599942 270)
			(size 0.762 0.762)
			(drill 0.359918)
			(layers "*.Cu" "*.Mask")
			(remove_unused_layers no)
			(net "PCIE_COMP_B_TO_SCC_B_RST_0")
			(clearance 0.1651)
			(thermal_gap 0.1651)
		)
		(pad "C8" thru_hole circle
			(at 12.599924 4.59994 270)
			(size 0.762 0.762)
			(drill 0.359918)
			(layers "*.Cu" "*.Mask")
			(remove_unused_layers no)
			(net "I2C_BMC_B_EXP_B_SCL")
			(clearance 0.1651)
			(thermal_gap 0.1651)
		)
		(pad "D1" thru_hole circle
			(at 0 4.99999 270)
			(size 0.762 0.762)
			(drill 0.359918)
			(layers "*.Cu" "*.Mask")
			(remove_unused_layers no)
			(net "PCIE_COMP_B_TO_SCC_B_CLK_0_DN")
			(clearance 0.1651)
			(thermal_gap 0.1651)
		)
		(pad "D2" thru_hole circle
			(at 1.800098 5.999988 270)
			(size 0.762 0.762)
			(drill 0.359918)
			(layers "*.Cu" "*.Mask")
			(remove_unused_layers no)
			(net "I2C_BMC_A_EXP_B_SDA")
			(clearance 0.1651)
			(thermal_gap 0.1651)
		)
		(pad "D3" thru_hole circle
			(at 3.599942 4.99999 270)
			(size 0.762 0.762)
			(drill 0.359918)
			(layers "*.Cu" "*.Mask")
			(remove_unused_layers no)
			(net "I2C_SCC_B_SDA_BUF")
			(clearance 0.1651)
			(thermal_gap 0.1651)
		)
		(pad "D4" thru_hole circle
			(at 5.40004 5.999988 270)
			(size 0.762 0.762)
			(drill 0.359918)
			(layers "*.Cu" "*.Mask")
			(remove_unused_layers no)
			(net "Net_15")
			(clearance 0.1651)
			(thermal_gap 0.1651)
		)
		(pad "D5" thru_hole circle
			(at 7.199884 4.99999 270)
			(size 0.762 0.762)
			(drill 0.359918)
			(layers "*.Cu" "*.Mask")
			(remove_unused_layers no)
			(net "UART_IOC_B_RX")
			(clearance 0.1651)
			(thermal_gap 0.1651)
		)
		(pad "D6" thru_hole circle
			(at 8.999982 5.999988 270)
			(size 0.762 0.762)
			(drill 0.359918)
			(layers "*.Cu" "*.Mask")
			(remove_unused_layers no)
			(net "BMC_B_EXP_B_SPARE_1")
			(clearance 0.1651)
			(thermal_gap 0.1651)
		)
		(pad "D7" thru_hole circle
			(at 10.80008 4.99999 270)
			(size 0.762 0.762)
			(drill 0.359918)
			(layers "*.Cu" "*.Mask")
			(remove_unused_layers no)
			(net "BMC_A_HEARTBEAT")
			(clearance 0.1651)
			(thermal_gap 0.1651)
		)
		(pad "D8" thru_hole circle
			(at 12.599924 5.999988 270)
			(size 0.762 0.762)
			(drill 0.359918)
			(layers "*.Cu" "*.Mask")
			(remove_unused_layers no)
			(net "I2C_BMC_B_EXP_B_SDA")
			(clearance 0.1651)
			(thermal_gap 0.1651)
		)
		(pad "E1" thru_hole circle
			(at 0 7.199884 270)
			(size 0.762 0.762)
			(drill 0.359918)
			(layers "*.Cu" "*.Mask")
			(remove_unused_layers no)
			(net "PCIE_SCC_B_TO_COMP_B_0_DP")
			(clearance 0.1651)
			(thermal_gap 0.1651)
		)
		(pad "E2" thru_hole circle
			(at 1.800098 8.199882 270)
			(size 0.762 0.762)
			(drill 0.359918)
			(layers "*.Cu" "*.Mask")
			(remove_unused_layers no)
			(net "PCIE_SCC_B_TO_COMP_B_1_DP")
			(clearance 0.1651)
			(thermal_gap 0.1651)
		)
		(pad "E3" thru_hole circle
			(at 3.599942 7.199884 270)
			(size 0.762 0.762)
			(drill 0.359918)
			(layers "*.Cu" "*.Mask")
			(remove_unused_layers no)
			(net "PCIE_SCC_B_TO_COMP_B_2_DP")
			(clearance 0.1651)
			(thermal_gap 0.1651)
		)
		(pad "E4" thru_hole circle
			(at 5.40004 8.199882 270)
			(size 0.762 0.762)
			(drill 0.359918)
			(layers "*.Cu" "*.Mask")
			(remove_unused_layers no)
			(net "PCIE_SCC_B_TO_COMP_B_3_DP")
			(clearance 0.1651)
			(thermal_gap 0.1651)
		)
		(pad "E5" thru_hole circle
			(at 7.199884 7.199884 270)
			(size 0.762 0.762)
			(drill 0.359918)
			(layers "*.Cu" "*.Mask")
			(remove_unused_layers no)
			(net "PCIE_SCC_B_TO_COMP_B_4_DP")
			(clearance 0.1651)
			(thermal_gap 0.1651)
		)
		(pad "E6" thru_hole circle
			(at 8.999982 8.199882 270)
			(size 0.762 0.762)
			(drill 0.359918)
			(layers "*.Cu" "*.Mask")
			(remove_unused_layers no)
			(net "PCIE_SCC_B_TO_COMP_B_5_DP")
			(clearance 0.1651)
			(thermal_gap 0.1651)
		)
		(pad "E7" thru_hole circle
			(at 10.80008 7.199884 270)
			(size 0.762 0.762)
			(drill 0.359918)
			(layers "*.Cu" "*.Mask")
			(remove_unused_layers no)
			(net "PCIE_SCC_B_TO_COMP_B_6_DP")
			(clearance 0.1651)
			(thermal_gap 0.1651)
		)
		(pad "E8" thru_hole circle
			(at 12.599924 8.199882 270)
			(size 0.762 0.762)
			(drill 0.359918)
			(layers "*.Cu" "*.Mask")
			(remove_unused_layers no)
			(net "PCIE_SCC_B_TO_COMP_B_7_DP")
			(clearance 0.1651)
			(thermal_gap 0.1651)
		)
		(pad "F1" thru_hole circle
			(at 0 8.599932 270)
			(size 0.762 0.762)
			(drill 0.359918)
			(layers "*.Cu" "*.Mask")
			(remove_unused_layers no)
			(net "PCIE_SCC_B_TO_COMP_B_0_DN")
			(clearance 0.1651)
			(thermal_gap 0.1651)
		)
		(pad "F2" thru_hole circle
			(at 1.800098 9.59993 270)
			(size 0.762 0.762)
			(drill 0.359918)
			(layers "*.Cu" "*.Mask")
			(remove_unused_layers no)
			(net "PCIE_SCC_B_TO_COMP_B_1_DN")
			(clearance 0.1651)
			(thermal_gap 0.1651)
		)
		(pad "F3" thru_hole circle
			(at 3.599942 8.599932 270)
			(size 0.762 0.762)
			(drill 0.359918)
			(layers "*.Cu" "*.Mask")
			(remove_unused_layers no)
			(net "PCIE_SCC_B_TO_COMP_B_2_DN")
			(clearance 0.1651)
			(thermal_gap 0.1651)
		)
		(pad "F4" thru_hole circle
			(at 5.40004 9.59993 270)
			(size 0.762 0.762)
			(drill 0.359918)
			(layers "*.Cu" "*.Mask")
			(remove_unused_layers no)
			(net "PCIE_SCC_B_TO_COMP_B_3_DN")
			(clearance 0.1651)
			(thermal_gap 0.1651)
		)
		(pad "F5" thru_hole circle
			(at 7.199884 8.599932 270)
			(size 0.762 0.762)
			(drill 0.359918)
			(layers "*.Cu" "*.Mask")
			(remove_unused_layers no)
			(net "PCIE_SCC_B_TO_COMP_B_4_DN")
			(clearance 0.1651)
			(thermal_gap 0.1651)
		)
		(pad "F6" thru_hole circle
			(at 8.999982 9.59993 270)
			(size 0.762 0.762)
			(drill 0.359918)
			(layers "*.Cu" "*.Mask")
			(remove_unused_layers no)
			(net "PCIE_SCC_B_TO_COMP_B_5_DN")
			(clearance 0.1651)
			(thermal_gap 0.1651)
		)
		(pad "F7" thru_hole circle
			(at 10.80008 8.599932 270)
			(size 0.762 0.762)
			(drill 0.359918)
			(layers "*.Cu" "*.Mask")
			(remove_unused_layers no)
			(net "PCIE_SCC_B_TO_COMP_B_6_DN")
			(clearance 0.1651)
			(thermal_gap 0.1651)
		)
		(pad "F8" thru_hole circle
			(at 12.599924 9.59993 270)
			(size 0.762 0.762)
			(drill 0.359918)
			(layers "*.Cu" "*.Mask")
			(remove_unused_layers no)
			(net "PCIE_SCC_B_TO_COMP_B_7_DN")
			(clearance 0.1651)
			(thermal_gap 0.1651)
		)
		(pad "GND1" thru_hole circle
			(at 0 2.500122 270)
			(size 0.762 0.762)
			(drill 0.359918)
			(layers "*.Cu" "*.Mask")
			(remove_unused_layers no)
			(net "GND")
			(clearance 0.1651)
			(thermal_gap 0.1651)
		)
		(pad "GND2" thru_hole circle
			(at 0 6.100064 270)
			(size 0.762 0.762)
			(drill 0.359918)
			(layers "*.Cu" "*.Mask")
			(remove_unused_layers no)
			(net "GND")
			(clearance 0.1651)
			(thermal_gap 0.1651)
		)
		(pad "GND3" thru_hole circle
			(at 0 9.700006 270)
			(size 0.762 0.762)
			(drill 0.359918)
			(layers "*.Cu" "*.Mask")
			(remove_unused_layers no)
			(net "GND")
			(clearance 0.1651)
			(thermal_gap 0.1651)
		)
		(pad "GND4" thru_hole circle
			(at 1.800098 -0.100076 270)
			(size 0.762 0.762)
			(drill 0.359918)
			(layers "*.Cu" "*.Mask")
			(remove_unused_layers no)
			(net "GND")
			(clearance 0.1651)
			(thermal_gap 0.1651)
		)
		(pad "GND5" thru_hole circle
			(at 1.800098 3.50012 270)
			(size 0.762 0.762)
			(drill 0.359918)
			(layers "*.Cu" "*.Mask")
			(remove_unused_layers no)
			(net "GND")
			(clearance 0.1651)
			(thermal_gap 0.1651)
		)
		(pad "GND6" thru_hole circle
			(at 1.800098 7.100062 270)
			(size 0.762 0.762)
			(drill 0.359918)
			(layers "*.Cu" "*.Mask")
			(remove_unused_layers no)
			(net "GND")
			(clearance 0.1651)
			(thermal_gap 0.1651)
		)
		(pad "GND7" thru_hole circle
			(at 1.800098 10.700004 270)
			(size 0.762 0.762)
			(drill 0.359918)
			(layers "*.Cu" "*.Mask")
			(remove_unused_layers no)
			(net "GND")
			(clearance 0.1651)
			(thermal_gap 0.1651)
		)
		(pad "GND8" thru_hole circle
			(at 3.599942 2.500122 270)
			(size 0.762 0.762)
			(drill 0.359918)
			(layers "*.Cu" "*.Mask")
			(remove_unused_layers no)
			(net "GND")
			(clearance 0.1651)
			(thermal_gap 0.1651)
		)
		(pad "GND9" thru_hole circle
			(at 3.599942 6.100064 270)
			(size 0.762 0.762)
			(drill 0.359918)
			(layers "*.Cu" "*.Mask")
			(remove_unused_layers no)
			(net "GND")
			(clearance 0.1651)
			(thermal_gap 0.1651)
		)
		(pad "GND10" thru_hole circle
			(at 3.599942 9.700006 270)
			(size 0.762 0.762)
			(drill 0.359918)
			(layers "*.Cu" "*.Mask")
			(remove_unused_layers no)
			(net "GND")
			(clearance 0.1651)
			(thermal_gap 0.1651)
		)
		(pad "GND11" thru_hole circle
			(at 5.40004 -0.100076 270)
			(size 0.762 0.762)
			(drill 0.359918)
			(layers "*.Cu" "*.Mask")
			(remove_unused_layers no)
			(net "GND")
			(clearance 0.1651)
			(thermal_gap 0.1651)
		)
		(pad "GND12" thru_hole circle
			(at 5.40004 3.50012 270)
			(size 0.762 0.762)
			(drill 0.359918)
			(layers "*.Cu" "*.Mask")
			(remove_unused_layers no)
			(net "GND")
			(clearance 0.1651)
			(thermal_gap 0.1651)
		)
		(pad "GND13" thru_hole circle
			(at 5.40004 7.100062 270)
			(size 0.762 0.762)
			(drill 0.359918)
			(layers "*.Cu" "*.Mask")
			(remove_unused_layers no)
			(net "GND")
			(clearance 0.1651)
			(thermal_gap 0.1651)
		)
		(pad "GND14" thru_hole circle
			(at 5.40004 10.700004 270)
			(size 0.762 0.762)
			(drill 0.359918)
			(layers "*.Cu" "*.Mask")
			(remove_unused_layers no)
			(net "GND")
			(clearance 0.1651)
			(thermal_gap 0.1651)
		)
		(pad "GND15" thru_hole circle
			(at 7.199884 2.500122 270)
			(size 0.762 0.762)
			(drill 0.359918)
			(layers "*.Cu" "*.Mask")
			(remove_unused_layers no)
			(net "GND")
			(clearance 0.1651)
			(thermal_gap 0.1651)
		)
		(pad "GND16" thru_hole circle
			(at 7.199884 6.100064 270)
			(size 0.762 0.762)
			(drill 0.359918)
			(layers "*.Cu" "*.Mask")
			(remove_unused_layers no)
			(net "GND")
			(clearance 0.1651)
			(thermal_gap 0.1651)
		)
		(pad "GND17" thru_hole circle
			(at 7.199884 9.700006 270)
			(size 0.762 0.762)
			(drill 0.359918)
			(layers "*.Cu" "*.Mask")
			(remove_unused_layers no)
			(net "GND")
			(clearance 0.1651)
			(thermal_gap 0.1651)
		)
		(pad "GND18" thru_hole circle
			(at 8.999982 -0.100076 270)
			(size 0.762 0.762)
			(drill 0.359918)
			(layers "*.Cu" "*.Mask")
			(remove_unused_layers no)
			(net "GND")
			(clearance 0.1651)
			(thermal_gap 0.1651)
		)
		(pad "GND19" thru_hole circle
			(at 8.999982 3.50012 270)
			(size 0.762 0.762)
			(drill 0.359918)
			(layers "*.Cu" "*.Mask")
			(remove_unused_layers no)
			(net "GND")
			(clearance 0.1651)
			(thermal_gap 0.1651)
		)
		(pad "GND20" thru_hole circle
			(at 8.999982 7.100062 270)
			(size 0.762 0.762)
			(drill 0.359918)
			(layers "*.Cu" "*.Mask")
			(remove_unused_layers no)
			(net "GND")
			(clearance 0.1651)
			(thermal_gap 0.1651)
		)
		(pad "GND21" thru_hole circle
			(at 8.999982 10.700004 270)
			(size 0.762 0.762)
			(drill 0.359918)
			(layers "*.Cu" "*.Mask")
			(remove_unused_layers no)
			(net "GND")
			(clearance 0.1651)
			(thermal_gap 0.1651)
		)
		(pad "GND22" thru_hole circle
			(at 10.80008 2.500122 270)
			(size 0.762 0.762)
			(drill 0.359918)
			(layers "*.Cu" "*.Mask")
			(remove_unused_layers no)
			(net "GND")
			(clearance 0.1651)
			(thermal_gap 0.1651)
		)
		(pad "GND23" thru_hole circle
			(at 10.80008 6.100064 270)
			(size 0.762 0.762)
			(drill 0.359918)
			(layers "*.Cu" "*.Mask")
			(remove_unused_layers no)
			(net "GND")
			(clearance 0.1651)
			(thermal_gap 0.1651)
		)
		(pad "GND24" thru_hole circle
			(at 10.80008 9.700006 270)
			(size 0.762 0.762)
			(drill 0.359918)
			(layers "*.Cu" "*.Mask")
			(remove_unused_layers no)
			(net "GND")
			(clearance 0.1651)
			(thermal_gap 0.1651)
		)
		(pad "GND25" thru_hole circle
			(at 12.599924 -0.100076 270)
			(size 0.762 0.762)
			(drill 0.359918)
			(layers "*.Cu" "*.Mask")
			(remove_unused_layers no)
			(net "GND")
			(clearance 0.1651)
			(thermal_gap 0.1651)
		)
	)
)
